(kicad_pcb
	(version 20221018)
	(generator pcbnew)
	(general
    (thickness 1.7403)
  )
	(paper "A4")
	(title_block
    (title "Data Center RDIMM DDR4 Tester")
    (date "2024-09-30")
    (rev "1.2.4")
		(comment 9 "footprint 169 of 690 (U14), pads 1-113 of 291")
	)
	(layers
    (0 "F.Cu" signal)
    (1 "In1.Cu" power)
    (2 "In2.Cu" signal)
    (3 "In3.Cu" power)
    (4 "In4.Cu" power)
    (5 "In5.Cu" signal)
    (6 "In6.Cu" power)
    (7 "In7.Cu" signal)
    (8 "In8.Cu" power)
    (9 "In9.Cu" signal)
    (10 "In10.Cu" power)
    (31 "B.Cu" signal)
    (32 "B.Adhes" user "B.Adhesive")
    (33 "F.Adhes" user "F.Adhesive")
    (34 "B.Paste" user)
    (35 "F.Paste" user)
    (36 "B.SilkS" user "B.Silkscreen")
    (37 "F.SilkS" user "F.Silkscreen")
    (38 "B.Mask" user)
    (39 "F.Mask" user)
    (40 "Dwgs.User" user "User.Drawings")
    (41 "Cmts.User" user "User.Comments")
    (42 "Eco1.User" user "User.Eco1")
    (43 "Eco2.User" user "User.Eco2")
    (44 "Edge.Cuts" user)
    (45 "Margin" user)
    (46 "B.CrtYd" user "B.Courtyard")
    (47 "F.CrtYd" user "F.Courtyard")
    (48 "B.Fab" user)
    (49 "F.Fab" user)
  )
	(footprint "data-center-rdimm-ddr4-tester-footprints:Bus_DDR4_Socket_DIMM_2199155-1"
    (layer "F.Cu")
    (at 246.636328 55.060008 180)
    (property "Author" "Antmicro")
    (property "License" "Apache-2.0")
    (property "MPN" "2199155-1")
    (property "Manufacturer" "TE Connectivity")
    (property "Sheetfile" "DDR4.kicad_sch")
    (property "Sheetname" "DDR4")
    (property "ki_description" "DDR4 RDIMM 288 Pin SMT type")
    (attr smd)
    (fp_text reference "U14" (at -5.583672 1.360008 180) (layer "F.SilkS")
        (effects (font (size 0.7 0.7) (thickness 0.15)) (justify left bottom))
    )
    (fp_text value "Bus_DDR4_2199155-1" (at -7.9 2.3 180) (layer "F.Fab") hide
        (effects (font (size 0.7 0.7) (thickness 0.15)) (justify left bottom))
    )
    (pad "1" smd rect (at 0 0 270) (size 1.8 0.57) (layers "F.Cu" "F.Paste" "F.Mask")
      (net 308 "NC") (pinfunction "12V/NC") (pintype "passive"))
    (pad "2" smd rect (at 0.848 0 270) (size 1.8 0.57) (layers "F.Cu" "F.Paste" "F.Mask")
      (net 9 "GND") (pinfunction "VSS") (pintype "passive"))
    (pad "3" smd rect (at 1.699 0 270) (size 1.8 0.57) (layers "F.Cu" "F.Paste" "F.Mask")
      (net 241 "DQ4") (pinfunction "DQ4") (pintype "passive"))
    (pad "4" smd rect (at 2.548 0 270) (size 1.8 0.57) (layers "F.Cu" "F.Paste" "F.Mask")
      (net 9 "GND") (pinfunction "VSS") (pintype "passive"))
    (pad "5" smd rect (at 3.398 0 270) (size 1.8 0.57) (layers "F.Cu" "F.Paste" "F.Mask")
      (net 242 "DQ0") (pinfunction "DQ0") (pintype "passive"))
    (pad "6" smd rect (at 4.248 0 270) (size 1.8 0.57) (layers "F.Cu" "F.Paste" "F.Mask")
      (net 9 "GND") (pinfunction "VSS") (pintype "passive"))
    (pad "7" smd rect (at 5.099 0 270) (size 1.8 0.57) (layers "F.Cu" "F.Paste" "F.Mask")
      (net 316 "DQS9_P") (pinfunction "DQS9_t") (pintype "passive"))
    (pad "8" smd rect (at 5.95 0 270) (size 1.8 0.57) (layers "F.Cu" "F.Paste" "F.Mask")
      (net 317 "DQS9_N") (pinfunction "DQS9_c") (pintype "passive"))
    (pad "9" smd rect (at 6.799 0 270) (size 1.8 0.57) (layers "F.Cu" "F.Paste" "F.Mask")
      (net 9 "GND") (pinfunction "VSS") (pintype "passive"))
    (pad "10" smd rect (at 7.65 0 270) (size 1.8 0.57) (layers "F.Cu" "F.Paste" "F.Mask")
      (net 244 "DQ6") (pinfunction "DQ6") (pintype "passive"))
    (pad "11" smd rect (at 8.499 0 270) (size 1.8 0.57) (layers "F.Cu" "F.Paste" "F.Mask")
      (net 9 "GND") (pinfunction "VSS") (pintype "passive"))
    (pad "12" smd rect (at 9.349 0 270) (size 1.8 0.57) (layers "F.Cu" "F.Paste" "F.Mask")
      (net 243 "DQ2") (pinfunction "DQ2") (pintype "passive"))
    (pad "13" smd rect (at 10.198 0 270) (size 1.8 0.57) (layers "F.Cu" "F.Paste" "F.Mask")
      (net 9 "GND") (pinfunction "VSS") (pintype "passive"))
    (pad "14" smd rect (at 11.05 0 270) (size 1.8 0.57) (layers "F.Cu" "F.Paste" "F.Mask")
      (net 245 "DQ12") (pinfunction "DQ12") (pintype "passive"))
    (pad "15" smd rect (at 11.9 0 270) (size 1.8 0.57) (layers "F.Cu" "F.Paste" "F.Mask")
      (net 9 "GND") (pinfunction "VSS") (pintype "passive"))
    (pad "16" smd rect (at 12.749 0 270) (size 1.8 0.57) (layers "F.Cu" "F.Paste" "F.Mask")
      (net 246 "DQ8") (pinfunction "DQ8") (pintype "passive"))
    (pad "17" smd rect (at 13.598 0 270) (size 1.8 0.57) (layers "F.Cu" "F.Paste" "F.Mask")
      (net 9 "GND") (pinfunction "VSS") (pintype "passive"))
    (pad "18" smd rect (at 14.448 0 270) (size 1.8 0.57) (layers "F.Cu" "F.Paste" "F.Mask")
      (net 319 "DQS10_P") (pinfunction "DQS10_t") (pintype "passive"))
    (pad "19" smd rect (at 15.3 0 270) (size 1.8 0.57) (layers "F.Cu" "F.Paste" "F.Mask")
      (net 321 "DQS10_N") (pinfunction "DQS10_c") (pintype "passive"))
    (pad "20" smd rect (at 16.149 0 270) (size 1.8 0.57) (layers "F.Cu" "F.Paste" "F.Mask")
      (net 9 "GND") (pinfunction "VSS") (pintype "passive"))
    (pad "21" smd rect (at 16.998 0 270) (size 1.8 0.57) (layers "F.Cu" "F.Paste" "F.Mask")
      (net 247 "DQ14") (pinfunction "DQ14") (pintype "passive"))
    (pad "22" smd rect (at 17.85 0 270) (size 1.8 0.57) (layers "F.Cu" "F.Paste" "F.Mask")
      (net 9 "GND") (pinfunction "VSS") (pintype "passive"))
    (pad "23" smd rect (at 18.699 0 270) (size 1.8 0.57) (layers "F.Cu" "F.Paste" "F.Mask")
      (net 248 "DQ10") (pinfunction "DQ10") (pintype "passive"))
    (pad "24" smd rect (at 19.55 0 270) (size 1.8 0.57) (layers "F.Cu" "F.Paste" "F.Mask")
      (net 9 "GND") (pinfunction "VSS") (pintype "passive"))
    (pad "25" smd rect (at 20.399 0 270) (size 1.8 0.57) (layers "F.Cu" "F.Paste" "F.Mask")
      (net 249 "DQ20") (pinfunction "DQ20") (pintype "passive"))
    (pad "26" smd rect (at 21.248 0 270) (size 1.8 0.57) (layers "F.Cu" "F.Paste" "F.Mask")
      (net 9 "GND") (pinfunction "VSS") (pintype "passive"))
    (pad "27" smd rect (at 22.1 0 270) (size 1.8 0.57) (layers "F.Cu" "F.Paste" "F.Mask")
      (net 250 "DQ16") (pinfunction "DQ16") (pintype "passive"))
    (pad "28" smd rect (at 22.949 0 270) (size 1.8 0.57) (layers "F.Cu" "F.Paste" "F.Mask")
      (net 9 "GND") (pinfunction "VSS") (pintype "passive"))
    (pad "29" smd rect (at 23.8 0 270) (size 1.8 0.57) (layers "F.Cu" "F.Paste" "F.Mask")
      (net 323 "DQS11_P") (pinfunction "DQS11_t") (pintype "passive"))
    (pad "30" smd rect (at 24.649 0 270) (size 1.8 0.57) (layers "F.Cu" "F.Paste" "F.Mask")
      (net 325 "DQS11_N") (pinfunction "DQS11_c") (pintype "passive"))
    (pad "31" smd rect (at 25.498 0 270) (size 1.8 0.57) (layers "F.Cu" "F.Paste" "F.Mask")
      (net 9 "GND") (pinfunction "VSS") (pintype "passive"))
    (pad "32" smd rect (at 26.35 0 270) (size 1.8 0.57) (layers "F.Cu" "F.Paste" "F.Mask")
      (net 251 "DQ22") (pinfunction "DQ22") (pintype "passive"))
    (pad "33" smd rect (at 27.199 0 270) (size 1.8 0.57) (layers "F.Cu" "F.Paste" "F.Mask")
      (net 9 "GND") (pinfunction "VSS") (pintype "passive"))
    (pad "34" smd rect (at 28.05 0 270) (size 1.8 0.57) (layers "F.Cu" "F.Paste" "F.Mask")
      (net 253 "DQ18") (pinfunction "DQ18") (pintype "passive"))
    (pad "35" smd rect (at 28.899 0 270) (size 1.8 0.57) (layers "F.Cu" "F.Paste" "F.Mask")
      (net 9 "GND") (pinfunction "VSS") (pintype "passive"))
    (pad "36" smd rect (at 29.749 0 270) (size 1.8 0.57) (layers "F.Cu" "F.Paste" "F.Mask")
      (net 252 "DQ28") (pinfunction "DQ28") (pintype "passive"))
    (pad "37" smd rect (at 30.6 0 270) (size 1.8 0.57) (layers "F.Cu" "F.Paste" "F.Mask")
      (net 9 "GND") (pinfunction "VSS") (pintype "passive"))
    (pad "38" smd rect (at 31.449 0 270) (size 1.8 0.57) (layers "F.Cu" "F.Paste" "F.Mask")
      (net 254 "DQ24") (pinfunction "DQ24") (pintype "passive"))
    (pad "39" smd rect (at 32.298 0 270) (size 1.8 0.57) (layers "F.Cu" "F.Paste" "F.Mask")
      (net 9 "GND") (pinfunction "VSS") (pintype "passive"))
    (pad "40" smd rect (at 33.149 0 270) (size 1.8 0.57) (layers "F.Cu" "F.Paste" "F.Mask")
      (net 327 "DQS12_P") (pinfunction "DQS12_t") (pintype "passive"))
    (pad "41" smd rect (at 33.999 0 270) (size 1.8 0.57) (layers "F.Cu" "F.Paste" "F.Mask")
      (net 329 "DQS12_N") (pinfunction "DQS12_c") (pintype "passive"))
    (pad "42" smd rect (at 34.85 0 270) (size 1.8 0.57) (layers "F.Cu" "F.Paste" "F.Mask")
      (net 9 "GND") (pinfunction "VSS") (pintype "passive"))
    (pad "43" smd rect (at 35.7 0 270) (size 1.8 0.57) (layers "F.Cu" "F.Paste" "F.Mask")
      (net 255 "DQ30") (pinfunction "DQ30") (pintype "passive"))
    (pad "44" smd rect (at 36.548 0 270) (size 1.8 0.57) (layers "F.Cu" "F.Paste" "F.Mask")
      (net 9 "GND") (pinfunction "VSS") (pintype "passive"))
    (pad "45" smd rect (at 37.399 0 270) (size 1.8 0.57) (layers "F.Cu" "F.Paste" "F.Mask")
      (net 256 "DQ26") (pinfunction "DQ26") (pintype "passive"))
    (pad "46" smd rect (at 38.249 0 270) (size 1.8 0.57) (layers "F.Cu" "F.Paste" "F.Mask")
      (net 9 "GND") (pinfunction "VSS") (pintype "passive"))
    (pad "47" smd rect (at 39.1 0 270) (size 1.8 0.57) (layers "F.Cu" "F.Paste" "F.Mask")
      (net 257 "CB4") (pinfunction "CB4") (pintype "passive"))
    (pad "48" smd rect (at 39.95 0 270) (size 1.8 0.57) (layers "F.Cu" "F.Paste" "F.Mask")
      (net 9 "GND") (pinfunction "VSS") (pintype "passive"))
    (pad "49" smd rect (at 40.798 0 270) (size 1.8 0.57) (layers "F.Cu" "F.Paste" "F.Mask")
      (net 258 "CB0") (pinfunction "CB0") (pintype "passive"))
    (pad "50" smd rect (at 41.649 0 270) (size 1.8 0.57) (layers "F.Cu" "F.Paste" "F.Mask")
      (net 9 "GND") (pinfunction "VSS") (pintype "passive"))
    (pad "51" smd rect (at 42.499 0 270) (size 1.8 0.57) (layers "F.Cu" "F.Paste" "F.Mask")
      (net 347 "DQS17_P") (pinfunction "DQS17_t") (pintype "passive"))
    (pad "52" smd rect (at 43.35 0 270) (size 1.8 0.57) (layers "F.Cu" "F.Paste" "F.Mask")
      (net 349 "DQS17_N") (pinfunction "DQS17_c") (pintype "passive"))
    (pad "53" smd rect (at 44.2 0 270) (size 1.8 0.57) (layers "F.Cu" "F.Paste" "F.Mask")
      (net 9 "GND") (pinfunction "VSS") (pintype "passive"))
    (pad "54" smd rect (at 45.048 0 270) (size 1.8 0.57) (layers "F.Cu" "F.Paste" "F.Mask")
      (net 259 "CB6") (pinfunction "CB6") (pintype "passive"))
    (pad "55" smd rect (at 45.898 0 270) (size 1.8 0.57) (layers "F.Cu" "F.Paste" "F.Mask")
      (net 9 "GND") (pinfunction "VSS") (pintype "passive"))
    (pad "56" smd rect (at 46.749 0 270) (size 1.8 0.57) (layers "F.Cu" "F.Paste" "F.Mask")
      (net 260 "CB2") (pinfunction "CB2") (pintype "passive"))
    (pad "57" smd rect (at 47.6 0 270) (size 1.8 0.57) (layers "F.Cu" "F.Paste" "F.Mask")
      (net 789 "DDR_PRESENCE") (pinfunction "Presence") (pintype "passive"))
    (pad "58" smd rect (at 48.45 0 270) (size 1.8 0.57) (layers "F.Cu" "F.Paste" "F.Mask")
      (net 262 "~{RESET}") (pinfunction "RESET_n") (pintype "passive"))
    (pad "59" smd rect (at 49.298 0 270) (size 1.8 0.57) (layers "F.Cu" "F.Paste" "F.Mask")
      (net 77 "VDDQ") (pinfunction "VDD") (pintype "passive"))
    (pad "60" smd rect (at 50.148 0 270) (size 1.8 0.57) (layers "F.Cu" "F.Paste" "F.Mask")
      (net 261 "CKE0") (pinfunction "CKE0") (pintype "passive"))
    (pad "61" smd rect (at 50.999 0 270) (size 1.8 0.57) (layers "F.Cu" "F.Paste" "F.Mask")
      (net 77 "VDDQ") (pinfunction "VDD") (pintype "passive"))
    (pad "62" smd rect (at 51.85 0 270) (size 1.8 0.57) (layers "F.Cu" "F.Paste" "F.Mask")
      (net 264 "~{ACT}") (pinfunction "ACT_n") (pintype "passive"))
    (pad "63" smd rect (at 52.7 0 270) (size 1.8 0.57) (layers "F.Cu" "F.Paste" "F.Mask")
      (net 263 "BG0") (pinfunction "BG0") (pintype "passive"))
    (pad "64" smd rect (at 53.548 0 270) (size 1.8 0.57) (layers "F.Cu" "F.Paste" "F.Mask")
      (net 77 "VDDQ") (pinfunction "VDD") (pintype "passive"))
    (pad "65" smd rect (at 54.398 0 270) (size 1.8 0.57) (layers "F.Cu" "F.Paste" "F.Mask")
      (net 265 "A12\\~{BC}") (pinfunction "A12/BC_n") (pintype "passive"))
    (pad "66" smd rect (at 55.249 0 270) (size 1.8 0.57) (layers "F.Cu" "F.Paste" "F.Mask")
      (net 266 "A9") (pinfunction "A9") (pintype "passive"))
    (pad "67" smd rect (at 56.1 0 270) (size 1.8 0.57) (layers "F.Cu" "F.Paste" "F.Mask")
      (net 77 "VDDQ") (pinfunction "VDD") (pintype "passive"))
    (pad "68" smd rect (at 56.95 0 270) (size 1.8 0.57) (layers "F.Cu" "F.Paste" "F.Mask")
      (net 268 "A8") (pinfunction "A8") (pintype "passive"))
    (pad "69" smd rect (at 57.798 0 270) (size 1.8 0.57) (layers "F.Cu" "F.Paste" "F.Mask")
      (net 267 "A6") (pinfunction "A6") (pintype "passive"))
    (pad "70" smd rect (at 58.648 0 270) (size 1.8 0.57) (layers "F.Cu" "F.Paste" "F.Mask")
      (net 77 "VDDQ") (pinfunction "VDD") (pintype "passive"))
    (pad "71" smd rect (at 59.499 0 270) (size 1.8 0.57) (layers "F.Cu" "F.Paste" "F.Mask")
      (net 269 "A3") (pinfunction "A3") (pintype "passive"))
    (pad "72" smd rect (at 60.35 0 270) (size 1.8 0.57) (layers "F.Cu" "F.Paste" "F.Mask")
      (net 270 "A1") (pinfunction "A1") (pintype "passive"))
    (pad "73" smd rect (at 61.2 0 270) (size 1.8 0.57) (layers "F.Cu" "F.Paste" "F.Mask")
      (net 77 "VDDQ") (pinfunction "VDD") (pintype "passive"))
    (pad "74" smd rect (at 62.048 0 270) (size 1.8 0.57) (layers "F.Cu" "F.Paste" "F.Mask")
      (net 355 "CK0_P") (pinfunction "CK0_t") (pintype "passive"))
    (pad "75" smd rect (at 62.898 0 270) (size 1.8 0.57) (layers "F.Cu" "F.Paste" "F.Mask")
      (net 356 "CK0_N") (pinfunction "CK0_c") (pintype "passive"))
    (pad "76" smd rect (at 63.749 0 270) (size 1.8 0.57) (layers "F.Cu" "F.Paste" "F.Mask")
      (net 77 "VDDQ") (pinfunction "VDD") (pintype "passive"))
    (pad "77" smd rect (at 64.599 0 270) (size 1.8 0.57) (layers "F.Cu" "F.Paste" "F.Mask")
      (net 186 "VTT") (pinfunction "VTT") (pintype "passive"))
    (pad "78" smd rect (at 70.549 0 270) (size 1.8 0.57) (layers "F.Cu" "F.Paste" "F.Mask")
      (net 187 "~{EVENT}") (pinfunction "EVENT_n") (pintype "passive"))
    (pad "79" smd rect (at 71.4 0 270) (size 1.8 0.57) (layers "F.Cu" "F.Paste" "F.Mask")
      (net 240 "A0") (pinfunction "A0") (pintype "passive"))
    (pad "80" smd rect (at 72.248 0 270) (size 1.8 0.57) (layers "F.Cu" "F.Paste" "F.Mask")
      (net 77 "VDDQ") (pinfunction "VDD") (pintype "passive"))
    (pad "81" smd rect (at 73.099 0 270) (size 1.8 0.57) (layers "F.Cu" "F.Paste" "F.Mask")
      (net 239 "BA0") (pinfunction "BA0") (pintype "passive"))
    (pad "82" smd rect (at 73.95 0 270) (size 1.8 0.57) (layers "F.Cu" "F.Paste" "F.Mask")
      (net 238 "~{RAS}\\A16") (pinfunction "RAS_n/A16") (pintype "passive"))
    (pad "83" smd rect (at 74.799 0 270) (size 1.8 0.57) (layers "F.Cu" "F.Paste" "F.Mask")
      (net 77 "VDDQ") (pinfunction "VDD") (pintype "passive"))
    (pad "84" smd rect (at 75.65 0 270) (size 1.8 0.57) (layers "F.Cu" "F.Paste" "F.Mask")
      (net 237 "~{CS0}") (pinfunction "CS0_n") (pintype "passive"))
    (pad "85" smd rect (at 76.498 0 270) (size 1.8 0.57) (layers "F.Cu" "F.Paste" "F.Mask")
      (net 77 "VDDQ") (pinfunction "VDD") (pintype "passive"))
    (pad "86" smd rect (at 77.349 0 270) (size 1.8 0.57) (layers "F.Cu" "F.Paste" "F.Mask")
      (net 236 "~{CAS}\\A15") (pinfunction "CAS_n/A15") (pintype "passive"))
    (pad "87" smd rect (at 78.2 0 270) (size 1.8 0.57) (layers "F.Cu" "F.Paste" "F.Mask")
      (net 235 "ODT0") (pinfunction "ODT0") (pintype "passive"))
    (pad "88" smd rect (at 79.049 0 270) (size 1.8 0.57) (layers "F.Cu" "F.Paste" "F.Mask")
      (net 77 "VDDQ") (pinfunction "VDD") (pintype "passive"))
    (pad "89" smd rect (at 79.9 0 270) (size 1.8 0.57) (layers "F.Cu" "F.Paste" "F.Mask")
      (net 234 "~{CS1}\\NC") (pinfunction "CS1_n") (pintype "passive"))
    (pad "90" smd rect (at 80.748 0 270) (size 1.8 0.57) (layers "F.Cu" "F.Paste" "F.Mask")
      (net 77 "VDDQ") (pinfunction "VDD") (pintype "passive"))
    (pad "91" smd rect (at 81.599 0 270) (size 1.8 0.57) (layers "F.Cu" "F.Paste" "F.Mask")
      (net 231 "ODT1\\NC") (pinfunction "ODT1") (pintype "passive"))
    (pad "92" smd rect (at 82.45 0 270) (size 1.8 0.57) (layers "F.Cu" "F.Paste" "F.Mask")
      (net 77 "VDDQ") (pinfunction "VDD") (pintype "passive"))
    (pad "93" smd rect (at 83.299 0 270) (size 1.8 0.57) (layers "F.Cu" "F.Paste" "F.Mask")
      (net 230 "~{CS2}\\C0") (pinfunction "C0/CS2_n") (pintype "passive"))
    (pad "94" smd rect (at 84.15 0 270) (size 1.8 0.57) (layers "F.Cu" "F.Paste" "F.Mask")
      (net 9 "GND") (pinfunction "VSS") (pintype "passive"))
    (pad "95" smd rect (at 84.998 0 270) (size 1.8 0.57) (layers "F.Cu" "F.Paste" "F.Mask")
      (net 233 "DQ36") (pinfunction "DQ36") (pintype "passive"))
    (pad "96" smd rect (at 85.849 0 270) (size 1.8 0.57) (layers "F.Cu" "F.Paste" "F.Mask")
      (net 9 "GND") (pinfunction "VSS") (pintype "passive"))
    (pad "97" smd rect (at 86.7 0 270) (size 1.8 0.57) (layers "F.Cu" "F.Paste" "F.Mask")
      (net 232 "DQ32") (pinfunction "DQ32") (pintype "passive"))
    (pad "98" smd rect (at 87.549 0 270) (size 1.8 0.57) (layers "F.Cu" "F.Paste" "F.Mask")
      (net 9 "GND") (pinfunction "VSS") (pintype "passive"))
    (pad "99" smd rect (at 88.4 0 270) (size 1.8 0.57) (layers "F.Cu" "F.Paste" "F.Mask")
      (net 331 "DQS13_P") (pinfunction "DQS13_t") (pintype "passive"))
    (pad "100" smd rect (at 89.248 0 270) (size 1.8 0.57) (layers "F.Cu" "F.Paste" "F.Mask")
      (net 333 "DQS13_N") (pinfunction "DQS13_c") (pintype "passive"))
    (pad "101" smd rect (at 90.099 0 270) (size 1.8 0.57) (layers "F.Cu" "F.Paste" "F.Mask")
      (net 9 "GND") (pinfunction "VSS") (pintype "passive"))
    (pad "102" smd rect (at 90.95 0 270) (size 1.8 0.57) (layers "F.Cu" "F.Paste" "F.Mask")
      (net 228 "DQ38") (pinfunction "DQ38") (pintype "passive"))
    (pad "103" smd rect (at 91.799 0 270) (size 1.8 0.57) (layers "F.Cu" "F.Paste" "F.Mask")
      (net 9 "GND") (pinfunction "VSS") (pintype "passive"))
    (pad "104" smd rect (at 92.65 0 270) (size 1.8 0.57) (layers "F.Cu" "F.Paste" "F.Mask")
      (net 227 "DQ34") (pinfunction "DQ34") (pintype "passive"))
    (pad "105" smd rect (at 93.498 0 270) (size 1.8 0.57) (layers "F.Cu" "F.Paste" "F.Mask")
      (net 9 "GND") (pinfunction "VSS") (pintype "passive"))
    (pad "106" smd rect (at 94.349 0 270) (size 1.8 0.57) (layers "F.Cu" "F.Paste" "F.Mask")
      (net 226 "DQ44") (pinfunction "DQ44") (pintype "passive"))
    (pad "107" smd rect (at 95.2 0 270) (size 1.8 0.57) (layers "F.Cu" "F.Paste" "F.Mask")
      (net 9 "GND") (pinfunction "VSS") (pintype "passive"))
    (pad "108" smd rect (at 96.049 0 270) (size 1.8 0.57) (layers "F.Cu" "F.Paste" "F.Mask")
      (net 229 "DQ40") (pinfunction "DQ40") (pintype "passive"))
    (pad "109" smd rect (at 96.9 0 270) (size 1.8 0.57) (layers "F.Cu" "F.Paste" "F.Mask")
      (net 9 "GND") (pinfunction "VSS") (pintype "passive"))
    (pad "110" smd rect (at 97.748 0 270) (size 1.8 0.57) (layers "F.Cu" "F.Paste" "F.Mask")
      (net 335 "DQS14_P") (pinfunction "DQS14_t") (pintype "passive"))
    (pad "111" smd rect (at 98.599 0 270) (size 1.8 0.57) (layers "F.Cu" "F.Paste" "F.Mask")
      (net 337 "DQS14_N") (pinfunction "DQS14_c") (pintype "passive"))
    (pad "112" smd rect (at 99.45 0 270) (size 1.8 0.57) (layers "F.Cu" "F.Paste" "F.Mask")
      (net 9 "GND") (pinfunction "VSS") (pintype "passive"))
    (pad "113" smd rect (at 100.299 0 270) (size 1.8 0.57) (layers "F.Cu" "F.Paste" "F.Mask")
      (net 222 "DQ46") (pinfunction "DQ46") (pintype "passive"))
  )
)
